# S9S_MB_2U (Grand Teton) — schematic netlist excerpt (pin names and nets, part order shuffled) for the footprints in the layout excerpt that follows; sources: Cadence DE-HDL packaged netlist, KiCad conversion of 03242023_DA0F0TMBIJ0_F0T_Motherboard_J_brd_V01_OCP.brd

C871  Q_CAP_DIFFBUS  DIFF BUS_0.22UF 6.3V 20% X6S  pkg C0201  page 174 : \1\ = P5E_CPU0_PE3_TX_C_DP<15> ; \2\ = P5E_CPU0_PE3_TX_DP<15>
R4669  Q_RES  160K 1% EMPTY  pkg 0402LF  page 306 : A = HSC_CSOUT ; B = A_HSC_HIGH
R4037  Q_RES  4.32K 1% CHIP  pkg 0402LF  page 225 : A = P3V3_AUX ; B = P0V62_CPU1_RST_DDR_VREF

(kicad_pcb
	(version 20260206)
	(generator "pcbnew")
	(generator_version "10.0")
	(general
		(thickness 1.6)
		(legacy_teardrops no)
	)
	(paper "A4")
	(title_block
		(title "03242023_DA0F0TMBIJ0_F0T_Motherboard_J_brd_V01_OCP.brd")
		(comment 1 "Grand Teton / footprints 367-369 of 6105")
	)
	(layers
		(0 "F.Cu" signal "TOP")
		(4 "In1.Cu" signal "GND")
		(6 "In2.Cu" signal "IN1")
		(8 "In3.Cu" signal "GND1")
		(10 "In4.Cu" signal "IN2")
		(12 "In5.Cu" signal "GND2")
		(14 "In6.Cu" signal "IN3")
		(16 "In7.Cu" signal "GND3")
		(18 "In8.Cu" signal "VCC")
		(20 "In9.Cu" signal "VCC1")
		(22 "In10.Cu" signal "GND4")
		(24 "In11.Cu" signal "IN4")
		(26 "In12.Cu" signal "GND5")
		(28 "In13.Cu" signal "IN5")
		(30 "In14.Cu" signal "GND6")
		(32 "In15.Cu" signal "IN6")
		(34 "In16.Cu" signal "GND7")
		(2 "B.Cu" signal "BOTTOM")
		(9 "F.Adhes" user "F.Adhesive")
		(11 "B.Adhes" user "B.Adhesive")
		(13 "F.Paste" user "Package Geometry/Pastemask Top")
		(15 "B.Paste" user "Package Geometry/Pastemask Bottom")
		(5 "F.SilkS" user "Ref Des/Silkscreen Top")
		(7 "B.SilkS" user "Ref Des/Silkscreen Bottom")
		(1 "F.Mask" user "Board Geometry/Soldermask Top")
		(3 "B.Mask" user "Board Geometry/Soldermask Bottom")
		(17 "Dwgs.User" user "User.Drawings")
		(19 "Cmts.User" user "User.Comments")
		(21 "Eco1.User" user "User.Eco1")
		(23 "Eco2.User" user "User.Eco2")
		(25 "Edge.Cuts" user "Board Geometry/Outline")
		(27 "Margin" user)
		(31 "F.CrtYd" user "Package Geometry/Place Bound Top")
		(29 "B.CrtYd" user "Package Geometry/Place Bound Bottom")
		(35 "F.Fab" user "Ref Des/Assembly Top")
		(33 "B.Fab" user "Ref Des/Assembly Bottom")
	)
	(footprint ""
		(layer "F.Cu")
		(at 281.758898 -424.54576 -90)
		(property "Reference" "R4669"
			(at 0 0 270)
			(layer "F.SilkS")
			(hide yes)
			(effects
				(font
					(size 1.27 1.27)
				)
			)
		)
		(property "Value" ""
			(at 0 0 270)
			(layer "F.Fab")
			(effects
				(font
					(size 1.27 1.27)
				)
			)
		)
		(duplicate_pad_numbers_are_jumpers no)
		(fp_line
			(start -0.7874 0.4064)
			(end -0.7874 -0.4064)
			(stroke
				(width 0.1524)
				(type default)
			)
			(layer "F.SilkS")
		)
		(fp_line
			(start 0.7874 0.4064)
			(end -0.7874 0.4064)
			(stroke
				(width 0.1524)
				(type default)
			)
			(layer "F.SilkS")
		)
		(fp_line
			(start -0.7874 -0.4064)
			(end 0.7874 -0.4064)
			(stroke
				(width 0.1524)
				(type default)
			)
			(layer "F.SilkS")
		)
		(fp_line
			(start 0.7874 -0.4064)
			(end 0.7874 0.4064)
			(stroke
				(width 0.1524)
				(type default)
			)
			(layer "F.SilkS")
		)
		(fp_line
			(start -0.67945 0.3048)
			(end -0.67945 -0.305054)
			(stroke
				(width 0.1)
				(type default)
			)
			(layer "F.Fab")
		)
		(fp_line
			(start -0.12065 0.3048)
			(end -0.67945 0.3048)
			(stroke
				(width 0.1)
				(type default)
			)
			(layer "F.Fab")
		)
		(fp_line
			(start 0.120396 0.3048)
			(end 0.120396 0.2794)
			(stroke
				(width 0.1)
				(type default)
			)
			(layer "F.Fab")
		)
		(fp_line
			(start 0.67945 0.3048)
			(end 0.120396 0.3048)
			(stroke
				(width 0.1)
				(type default)
			)
			(layer "F.Fab")
		)
		(fp_line
			(start -0.12065 0.2794)
			(end -0.12065 0.3048)
			(stroke
				(width 0.1)
				(type default)
			)
			(layer "F.Fab")
		)
		(fp_line
			(start 0.120396 0.2794)
			(end -0.12065 0.2794)
			(stroke
				(width 0.1)
				(type default)
			)
			(layer "F.Fab")
		)
		(fp_line
			(start -0.12065 -0.2794)
			(end 0.12065 -0.2794)
			(stroke
				(width 0.1)
				(type default)
			)
			(layer "F.Fab")
		)
		(fp_line
			(start 0.12065 -0.2794)
			(end 0.12065 -0.3048)
			(stroke
				(width 0.1)
				(type default)
			)
			(layer "F.Fab")
		)
		(fp_line
			(start 0.12065 -0.3048)
			(end 0.67945 -0.3048)
			(stroke
				(width 0.1)
				(type default)
			)
			(layer "F.Fab")
		)
		(fp_line
			(start 0.67945 -0.3048)
			(end 0.67945 0.3048)
			(stroke
				(width 0.1)
				(type default)
			)
			(layer "F.Fab")
		)
		(fp_line
			(start -0.67945 -0.305054)
			(end -0.12065 -0.305054)
			(stroke
				(width 0.1)
				(type default)
			)
			(layer "F.Fab")
		)
		(fp_line
			(start -0.12065 -0.305054)
			(end -0.12065 -0.2794)
			(stroke
				(width 0.1)
				(type default)
			)
			(layer "F.Fab")
		)
		(pad "1" smd circle
			(at -0.40005 0 270)
			(size 0 0)
			(layers "F.Cu" "F.Mask" "F.Paste")
			(net "HSC_CSOUT")
		)
		(pad "2" smd circle
			(at 0.40005 0 270)
			(size 0 0)
			(layers "F.Cu" "F.Mask" "F.Paste")
			(net "A_HSC_HIGH")
		)
	)
	(footprint ""
		(layer "F.Cu")
		(at 373.65813 -408.517344 -90)
		(property "Reference" "C871"
			(at 0 0 270)
			(layer "F.SilkS")
			(hide yes)
			(effects
				(font
					(size 1.27 1.27)
				)
			)
		)
		(property "Value" ""
			(at 0 0 270)
			(layer "F.Fab")
			(effects
				(font
					(size 1.27 1.27)
				)
			)
		)
		(duplicate_pad_numbers_are_jumpers no)
		(fp_line
			(start -0.299974 0.150114)
			(end -0.299974 -0.150114)
			(stroke
				(width 0.1)
				(type default)
			)
			(layer "F.Fab")
		)
		(fp_line
			(start 0.299974 0.150114)
			(end -0.299974 0.150114)
			(stroke
				(width 0.1)
				(type default)
			)
			(layer "F.Fab")
		)
		(fp_line
			(start -0.299974 -0.150114)
			(end 0.299974 -0.150114)
			(stroke
				(width 0.1)
				(type default)
			)
			(layer "F.Fab")
		)
		(fp_line
			(start 0.299974 -0.150114)
			(end 0.299974 0.150114)
			(stroke
				(width 0.1)
				(type default)
			)
			(layer "F.Fab")
		)
		(pad "1" smd rect
			(at -0.2667 0 270)
			(size 0.3048 0.381)
			(layers "F.Cu" "F.Mask" "F.Paste")
			(net "P5E_CPU0_PE3_TX_C_DP<15>")
		)
		(pad "2" smd rect
			(at 0.2667 0 270)
			(size 0.3048 0.381)
			(layers "F.Cu" "F.Mask" "F.Paste")
			(net "P5E_CPU0_PE3_TX_DP<15>")
		)
	)
	(footprint ""
		(layer "F.Cu")
		(at 123.994926 -119.810784 -90)
		(property "Reference" "R4037"
			(at 0 0 270)
			(layer "F.SilkS")
			(hide yes)
			(effects
				(font
					(size 1.27 1.27)
				)
			)
		)
		(property "Value" ""
			(at 0 0 270)
			(layer "F.Fab")
			(effects
				(font
					(size 1.27 1.27)
				)
			)
		)
		(duplicate_pad_numbers_are_jumpers no)
		(fp_line
			(start -0.7874 0.4064)
			(end -0.7874 -0.4064)
			(stroke
				(width 0.1524)
				(type default)
			)
			(layer "F.SilkS")
		)
		(fp_line
			(start 0.7874 0.4064)
			(end -0.7874 0.4064)
			(stroke
				(width 0.1524)
				(type default)
			)
			(layer "F.SilkS")
		)
		(fp_line
			(start -0.7874 -0.4064)
			(end 0.7874 -0.4064)
			(stroke
				(width 0.1524)
				(type default)
			)
			(layer "F.SilkS")
		)
		(fp_line
			(start 0.7874 -0.4064)
			(end 0.7874 0.4064)
			(stroke
				(width 0.1524)
				(type default)
			)
			(layer "F.SilkS")
		)
		(fp_line
			(start -0.67945 0.3048)
			(end -0.67945 -0.305054)
			(stroke
				(width 0.1)
				(type default)
			)
			(layer "F.Fab")
		)
		(fp_line
			(start -0.12065 0.3048)
			(end -0.67945 0.3048)
			(stroke
				(width 0.1)
				(type default)
			)
			(layer "F.Fab")
		)
		(fp_line
			(start 0.120396 0.3048)
			(end 0.120396 0.2794)
			(stroke
				(width 0.1)
				(type default)
			)
			(layer "F.Fab")
		)
		(fp_line
			(start 0.67945 0.3048)
			(end 0.120396 0.3048)
			(stroke
				(width 0.1)
				(type default)
			)
			(layer "F.Fab")
		)
		(fp_line
			(start -0.12065 0.2794)
			(end -0.12065 0.3048)
			(stroke
				(width 0.1)
				(type default)
			)
			(layer "F.Fab")
		)
		(fp_line
			(start 0.120396 0.2794)
			(end -0.12065 0.2794)
			(stroke
				(width 0.1)
				(type default)
			)
			(layer "F.Fab")
		)
		(fp_line
			(start -0.12065 -0.2794)
			(end 0.12065 -0.2794)
			(stroke
				(width 0.1)
				(type default)
			)
			(layer "F.Fab")
		)
		(fp_line
			(start 0.12065 -0.2794)
			(end 0.12065 -0.3048)
			(stroke
				(width 0.1)
				(type default)
			)
			(layer "F.Fab")
		)
		(fp_line
			(start 0.12065 -0.3048)
			(end 0.67945 -0.3048)
			(stroke
				(width 0.1)
				(type default)
			)
			(layer "F.Fab")
		)
		(fp_line
			(start 0.67945 -0.3048)
			(end 0.67945 0.3048)
			(stroke
				(width 0.1)
				(type default)
			)
			(layer "F.Fab")
		)
		(fp_line
			(start -0.67945 -0.305054)
			(end -0.12065 -0.305054)
			(stroke
				(width 0.1)
				(type default)
			)
			(layer "F.Fab")
		)
		(fp_line
			(start -0.12065 -0.305054)
			(end -0.12065 -0.2794)
			(stroke
				(width 0.1)
				(type default)
			)
			(layer "F.Fab")
		)
		(pad "1" smd circle
			(at -0.40005 0 270)
			(size 0 0)
			(layers "F.Cu" "F.Mask" "F.Paste")
			(net "P3V3_AUX")
		)
		(pad "2" smd circle
			(at 0.40005 0 270)
			(size 0 0)
			(layers "F.Cu" "F.Mask" "F.Paste")
			(net "P0V62_CPU1_RST_DDR_VREF")
		)
	)
)
